(kicad_pcb
	(version 20260206)
	(generator "pcbnew")
	(generator_version "10.0")
	(general
		(thickness 1.6)
		(legacy_teardrops no)
	)
	(paper "A4")
	(title_block
		(title "01162023_DA0F0TEBIF0_F0T_Expander_BD_F_brd_V02_OCP.brd")
		(comment 1 "Grand Teton / footprints 6020-6025 of 9728")
	)
	(layers
		(0 "F.Cu" signal "TOP")
		(4 "In1.Cu" signal "GND")
		(6 "In2.Cu" signal "VCC")
		(8 "In3.Cu" signal "VCC1")
		(10 "In4.Cu" signal "GND1")
		(12 "In5.Cu" signal "IN1")
		(14 "In6.Cu" signal "GND2")
		(16 "In7.Cu" signal "IN2")
		(18 "In8.Cu" signal "GND3")
		(20 "In9.Cu" signal "IN3")
		(22 "In10.Cu" signal "GND4")
		(24 "In11.Cu" signal "IN4")
		(26 "In12.Cu" signal "GND5")
		(28 "In13.Cu" signal "IN5")
		(30 "In14.Cu" signal "GND6")
		(32 "In15.Cu" signal "IN6")
		(34 "In16.Cu" signal "GND7")
		(2 "B.Cu" signal "BOTTOM")
		(9 "F.Adhes" user "F.Adhesive")
		(11 "B.Adhes" user "B.Adhesive")
		(13 "F.Paste" user "Package Geometry/Pastemask Top")
		(15 "B.Paste" user "Package Geometry/Pastemask Bottom")
		(5 "F.SilkS" user "Ref Des/Silkscreen Top")
		(7 "B.SilkS" user "Ref Des/Silkscreen Bottom")
		(1 "F.Mask" user "Board Geometry/Soldermask Top")
		(3 "B.Mask" user "Board Geometry/Soldermask Bottom")
		(17 "Dwgs.User" user "User.Drawings")
		(19 "Cmts.User" user "User.Comments")
		(21 "Eco1.User" user "User.Eco1")
		(23 "Eco2.User" user "User.Eco2")
		(25 "Edge.Cuts" user "Board Geometry/Outline")
		(27 "Margin" user)
		(31 "F.CrtYd" user "Package Geometry/Place Bound Top")
		(29 "B.CrtYd" user "Package Geometry/Place Bound Bottom")
		(35 "F.Fab" user "Ref Des/Assembly Top")
		(33 "B.Fab" user "Ref Des/Assembly Bottom")
	)
	(footprint ""
		(layer "F.Cu")
		(at 330.63434 -33.631886 180)
		(property "Reference" "C512"
			(at 0 0 180)
			(layer "F.SilkS")
			(hide yes)
			(effects
				(font
					(size 1.27 1.27)
				)
			)
		)
		(property "Value" ""
			(at 0 0 180)
			(layer "F.Fab")
			(effects
				(font
					(size 1.27 1.27)
				)
			)
		)
		(duplicate_pad_numbers_are_jumpers no)
		(fp_line
			(start 0.299974 0.150114)
			(end -0.299974 0.150114)
			(stroke
				(width 0.1)
				(type default)
			)
			(layer "F.Fab")
		)
		(fp_line
			(start 0.299974 -0.150114)
			(end 0.299974 0.150114)
			(stroke
				(width 0.1)
				(type default)
			)
			(layer "F.Fab")
		)
		(fp_line
			(start -0.299974 0.150114)
			(end -0.299974 -0.150114)
			(stroke
				(width 0.1)
				(type default)
			)
			(layer "F.Fab")
		)
		(fp_line
			(start -0.299974 -0.150114)
			(end 0.299974 -0.150114)
			(stroke
				(width 0.1)
				(type default)
			)
			(layer "F.Fab")
		)
		(pad "1" smd rect
			(at -0.2667 0 180)
			(size 0.3048 0.381)
			(layers "F.Cu" "F.Mask" "F.Paste")
			(net "P5E_PEX2_STN2_TX_DN<35>")
		)
		(pad "2" smd rect
			(at 0.2667 0 180)
			(size 0.3048 0.381)
			(layers "F.Cu" "F.Mask" "F.Paste")
			(net "P5E_PEX2_STN2_TX_C_DN<35>")
		)
	)
	(footprint ""
		(layer "F.Cu")
		(at 352.232214 -156.337)
		(property "Reference" "R4822"
			(at 0 0 0)
			(layer "F.SilkS")
			(hide yes)
			(effects
				(font
					(size 1.27 1.27)
				)
			)
		)
		(property "Value" ""
			(at 0 0 0)
			(layer "F.Fab")
			(effects
				(font
					(size 1.27 1.27)
				)
			)
		)
		(duplicate_pad_numbers_are_jumpers no)
		(fp_line
			(start -0.7874 -0.4064)
			(end 0.7874 -0.4064)
			(stroke
				(width 0.1524)
				(type default)
			)
			(layer "F.SilkS")
		)
		(fp_line
			(start -0.7874 0.4064)
			(end -0.7874 -0.4064)
			(stroke
				(width 0.1524)
				(type default)
			)
			(layer "F.SilkS")
		)
		(fp_line
			(start 0.7874 -0.4064)
			(end 0.7874 0.4064)
			(stroke
				(width 0.1524)
				(type default)
			)
			(layer "F.SilkS")
		)
		(fp_line
			(start 0.7874 0.4064)
			(end -0.7874 0.4064)
			(stroke
				(width 0.1524)
				(type default)
			)
			(layer "F.SilkS")
		)
		(fp_line
			(start -0.67945 -0.305054)
			(end -0.12065 -0.305054)
			(stroke
				(width 0.1)
				(type default)
			)
			(layer "F.Fab")
		)
		(fp_line
			(start -0.67945 0.3048)
			(end -0.67945 -0.305054)
			(stroke
				(width 0.1)
				(type default)
			)
			(layer "F.Fab")
		)
		(fp_line
			(start -0.12065 -0.305054)
			(end -0.12065 -0.2794)
			(stroke
				(width 0.1)
				(type default)
			)
			(layer "F.Fab")
		)
		(fp_line
			(start -0.12065 -0.2794)
			(end 0.12065 -0.2794)
			(stroke
				(width 0.1)
				(type default)
			)
			(layer "F.Fab")
		)
		(fp_line
			(start -0.12065 0.2794)
			(end -0.12065 0.3048)
			(stroke
				(width 0.1)
				(type default)
			)
			(layer "F.Fab")
		)
		(fp_line
			(start -0.12065 0.3048)
			(end -0.67945 0.3048)
			(stroke
				(width 0.1)
				(type default)
			)
			(layer "F.Fab")
		)
		(fp_line
			(start 0.120396 0.2794)
			(end -0.12065 0.2794)
			(stroke
				(width 0.1)
				(type default)
			)
			(layer "F.Fab")
		)
		(fp_line
			(start 0.120396 0.3048)
			(end 0.120396 0.2794)
			(stroke
				(width 0.1)
				(type default)
			)
			(layer "F.Fab")
		)
		(fp_line
			(start 0.12065 -0.3048)
			(end 0.67945 -0.3048)
			(stroke
				(width 0.1)
				(type default)
			)
			(layer "F.Fab")
		)
		(fp_line
			(start 0.12065 -0.2794)
			(end 0.12065 -0.3048)
			(stroke
				(width 0.1)
				(type default)
			)
			(layer "F.Fab")
		)
		(fp_line
			(start 0.67945 -0.3048)
			(end 0.67945 0.3048)
			(stroke
				(width 0.1)
				(type default)
			)
			(layer "F.Fab")
		)
		(fp_line
			(start 0.67945 0.3048)
			(end 0.120396 0.3048)
			(stroke
				(width 0.1)
				(type default)
			)
			(layer "F.Fab")
		)
		(pad "1" smd circle
			(at -0.40005 0)
			(size 0 0)
			(layers "F.Cu" "F.Mask" "F.Paste")
			(net "RST_PEX_NIC6_PERST_N")
		)
		(pad "2" smd circle
			(at 0.40005 0)
			(size 0 0)
			(layers "F.Cu" "F.Mask" "F.Paste")
			(net "RST_PEX_NIC6_PERST_R_N")
		)
	)
	(footprint ""
		(layer "F.Cu")
		(at 243.271802 -181.85892 -90)
		(property "Reference" "U325"
			(at 1.333246 -2.302002 90)
			(unlocked yes)
			(layer "F.SilkS")
			(effects
				(font
					(size 0.7874 0.5842)
					(thickness 0.1524)
				)
				(justify left)
			)
		)
		(property "Value" ""
			(at 0 0 270)
			(layer "F.Fab")
			(effects
				(font
					(size 1.27 1.27)
				)
			)
		)
		(duplicate_pad_numbers_are_jumpers no)
		(fp_line
			(start -2.0574 1.651)
			(end -2.0574 -1.651)
			(stroke
				(width 0.1524)
				(type default)
			)
			(layer "F.SilkS")
		)
		(fp_line
			(start 2.0574 1.651)
			(end -2.0574 1.651)
			(stroke
				(width 0.1524)
				(type default)
			)
			(layer "F.SilkS")
		)
		(fp_line
			(start 0 -1.016)
			(end 0.381 -1.651)
			(stroke
				(width 0.1524)
				(type default)
			)
			(layer "F.SilkS")
		)
		(fp_line
			(start -2.0574 -1.651)
			(end -0.381 -1.651)
			(stroke
				(width 0.1524)
				(type default)
			)
			(layer "F.SilkS")
		)
		(fp_line
			(start -0.381 -1.651)
			(end 0 -1.016)
			(stroke
				(width 0.1524)
				(type default)
			)
			(layer "F.SilkS")
		)
		(fp_line
			(start 0.381 -1.651)
			(end 2.0574 -1.651)
			(stroke
				(width 0.1524)
				(type default)
			)
			(layer "F.SilkS")
		)
		(fp_line
			(start 2.0574 -1.651)
			(end 2.0574 1.651)
			(stroke
				(width 0.1524)
				(type default)
			)
			(layer "F.SilkS")
		)
		(fp_poly
			(pts
				(xy -2.71272 -0.719328) (xy -2.71272 -1.344168) (xy -2.159 -1.016)
			)
			(stroke
				(width 0)
				(type default)
			)
			(fill yes)
			(layer "F.SilkS")
		)
		(fp_line
			(start -0.899922 1.549908)
			(end -0.899922 1.199896)
			(stroke
				(width 0.1)
				(type default)
			)
			(layer "F.Fab")
		)
		(fp_line
			(start 0.899922 1.549908)
			(end -0.899922 1.549908)
			(stroke
				(width 0.1)
				(type default)
			)
			(layer "F.Fab")
		)
		(fp_line
			(start -1.599946 1.199896)
			(end -1.599946 -1.199896)
			(stroke
				(width 0.1)
				(type default)
			)
			(layer "F.Fab")
		)
		(fp_line
			(start -0.899922 1.199896)
			(end -1.599946 1.199896)
			(stroke
				(width 0.1)
				(type default)
			)
			(layer "F.Fab")
		)
		(fp_line
			(start 0.899922 1.199896)
			(end 0.899922 1.549908)
			(stroke
				(width 0.1)
				(type default)
			)
			(layer "F.Fab")
		)
		(fp_line
			(start 1.599946 1.199896)
			(end 0.899922 1.199896)
			(stroke
				(width 0.1)
				(type default)
			)
			(layer "F.Fab")
		)
		(fp_line
			(start -1.599946 -1.199896)
			(end -0.899922 -1.199896)
			(stroke
				(width 0.1)
				(type default)
			)
			(layer "F.Fab")
		)
		(fp_line
			(start -0.899922 -1.199896)
			(end -0.899922 -1.549908)
			(stroke
				(width 0.1)
				(type default)
			)
			(layer "F.Fab")
		)
		(fp_line
			(start 0.899922 -1.199896)
			(end 1.599946 -1.199896)
			(stroke
				(width 0.1)
				(type default)
			)
			(layer "F.Fab")
		)
		(fp_line
			(start 1.599946 -1.199896)
			(end 1.599946 1.199896)
			(stroke
				(width 0.1)
				(type default)
			)
			(layer "F.Fab")
		)
		(fp_line
			(start -0.899922 -1.549908)
			(end 0.899922 -1.549908)
			(stroke
				(width 0.1)
				(type default)
			)
			(layer "F.Fab")
		)
		(fp_line
			(start 0.899922 -1.549908)
			(end 0.899922 -1.199896)
			(stroke
				(width 0.1)
				(type default)
			)
			(layer "F.Fab")
		)
		(fp_poly
			(pts
				(xy -2.71272 -0.719328) (xy -2.71272 -1.344168) (xy -2.159 -1.016)
			)
			(stroke
				(width 0)
				(type default)
			)
			(fill yes)
			(layer "F.Fab")
		)
		(pad "1" smd rect
			(at -1.225042 -0.94996 180)
			(size 0.5588 1.3462)
			(layers "F.Cu" "F.Mask" "F.Paste")
			(net "PWRGD_P1V2_AUX_RST")
		)
		(pad "2" smd rect
			(at -1.225042 0 180)
			(size 0.5588 1.3462)
			(layers "F.Cu" "F.Mask" "F.Paste")
			(net "BIC_RST_RSMRST_R_N")
		)
		(pad "3" smd rect
			(at -1.225042 0.94996 180)
			(size 0.5588 1.3462)
			(layers "F.Cu" "F.Mask" "F.Paste")
			(net "GND")
		)
		(pad "4" smd rect
			(at 1.225042 0.94996 180)
			(size 0.5588 1.3462)
			(layers "F.Cu" "F.Mask" "F.Paste")
			(net "BIC_RST_PWRGD_RSMRST_R")
		)
		(pad "5" smd rect
			(at 1.225042 -0.94996 180)
			(size 0.5588 1.3462)
			(layers "F.Cu" "F.Mask" "F.Paste")
			(net "P3V3_AUX")
		)
	)
	(footprint ""
		(layer "F.Cu")
		(at 429.302672 -89.1159)
		(property "Reference" "C963"
			(at 0 0 0)
			(layer "F.SilkS")
			(hide yes)
			(effects
				(font
					(size 1.27 1.27)
				)
			)
		)
		(property "Value" ""
			(at 0 0 0)
			(layer "F.Fab")
			(effects
				(font
					(size 1.27 1.27)
				)
			)
		)
		(duplicate_pad_numbers_are_jumpers no)
		(fp_line
			(start -0.7874 -0.4064)
			(end 0.7874 -0.4064)
			(stroke
				(width 0.1524)
				(type default)
			)
			(layer "F.SilkS")
		)
		(fp_line
			(start -0.7874 0.4064)
			(end -0.7874 -0.4064)
			(stroke
				(width 0.1524)
				(type default)
			)
			(layer "F.SilkS")
		)
		(fp_line
			(start 0.7874 -0.4064)
			(end 0.7874 0.4064)
			(stroke
				(width 0.1524)
				(type default)
			)
			(layer "F.SilkS")
		)
		(fp_line
			(start 0.7874 0.4064)
			(end -0.7874 0.4064)
			(stroke
				(width 0.1524)
				(type default)
			)
			(layer "F.SilkS")
		)
		(fp_line
			(start -0.67945 -0.305054)
			(end -0.12065 -0.305054)
			(stroke
				(width 0.1)
				(type default)
			)
			(layer "F.Fab")
		)
		(fp_line
			(start -0.67945 0.3048)
			(end -0.67945 -0.305054)
			(stroke
				(width 0.1)
				(type default)
			)
			(layer "F.Fab")
		)
		(fp_line
			(start -0.12065 -0.305054)
			(end -0.12065 -0.2794)
			(stroke
				(width 0.1)
				(type default)
			)
			(layer "F.Fab")
		)
		(fp_line
			(start -0.12065 -0.2794)
			(end 0.12065 -0.2794)
			(stroke
				(width 0.1)
				(type default)
			)
			(layer "F.Fab")
		)
		(fp_line
			(start -0.12065 0.2794)
			(end -0.12065 0.3048)
			(stroke
				(width 0.1)
				(type default)
			)
			(layer "F.Fab")
		)
		(fp_line
			(start -0.12065 0.3048)
			(end -0.67945 0.3048)
			(stroke
				(width 0.1)
				(type default)
			)
			(layer "F.Fab")
		)
		(fp_line
			(start 0.120396 0.2794)
			(end -0.12065 0.2794)
			(stroke
				(width 0.1)
				(type default)
			)
			(layer "F.Fab")
		)
		(fp_line
			(start 0.120396 0.3048)
			(end 0.120396 0.2794)
			(stroke
				(width 0.1)
				(type default)
			)
			(layer "F.Fab")
		)
		(fp_line
			(start 0.12065 -0.3048)
			(end 0.67945 -0.3048)
			(stroke
				(width 0.1)
				(type default)
			)
			(layer "F.Fab")
		)
		(fp_line
			(start 0.12065 -0.2794)
			(end 0.12065 -0.3048)
			(stroke
				(width 0.1)
				(type default)
			)
			(layer "F.Fab")
		)
		(fp_line
			(start 0.67945 -0.3048)
			(end 0.67945 0.3048)
			(stroke
				(width 0.1)
				(type default)
			)
			(layer "F.Fab")
		)
		(fp_line
			(start 0.67945 0.3048)
			(end 0.120396 0.3048)
			(stroke
				(width 0.1)
				(type default)
			)
			(layer "F.Fab")
		)
		(pad "1" smd circle
			(at -0.40005 0)
			(size 0 0)
			(layers "F.Cu" "F.Mask" "F.Paste")
			(net "P3V3_AUX")
		)
		(pad "2" smd circle
			(at 0.40005 0)
			(size 0 0)
			(layers "F.Cu" "F.Mask" "F.Paste")
			(net "GND")
		)
	)
	(footprint ""
		(layer "F.Cu")
		(at 220.34373 -48.93691 180)
		(property "Reference" "R589"
			(at 0 0 180)
			(layer "F.SilkS")
			(hide yes)
			(effects
				(font
					(size 1.27 1.27)
				)
			)
		)
		(property "Value" ""
			(at 0 0 180)
			(layer "F.Fab")
			(effects
				(font
					(size 1.27 1.27)
				)
			)
		)
		(duplicate_pad_numbers_are_jumpers no)
		(fp_line
			(start 0.7874 0.4064)
			(end -0.7874 0.4064)
			(stroke
				(width 0.1524)
				(type default)
			)
			(layer "F.SilkS")
		)
		(fp_line
			(start 0.7874 -0.4064)
			(end 0.7874 0.4064)
			(stroke
				(width 0.1524)
				(type default)
			)
			(layer "F.SilkS")
		)
		(fp_line
			(start -0.7874 0.4064)
			(end -0.7874 -0.4064)
			(stroke
				(width 0.1524)
				(type default)
			)
			(layer "F.SilkS")
		)
		(fp_line
			(start -0.7874 -0.4064)
			(end 0.7874 -0.4064)
			(stroke
				(width 0.1524)
				(type default)
			)
			(layer "F.SilkS")
		)
		(fp_line
			(start 0.67945 0.3048)
			(end 0.120396 0.3048)
			(stroke
				(width 0.1)
				(type default)
			)
			(layer "F.Fab")
		)
		(fp_line
			(start 0.67945 -0.3048)
			(end 0.67945 0.3048)
			(stroke
				(width 0.1)
				(type default)
			)
			(layer "F.Fab")
		)
		(fp_line
			(start 0.12065 -0.2794)
			(end 0.12065 -0.3048)
			(stroke
				(width 0.1)
				(type default)
			)
			(layer "F.Fab")
		)
		(fp_line
			(start 0.12065 -0.3048)
			(end 0.67945 -0.3048)
			(stroke
				(width 0.1)
				(type default)
			)
			(layer "F.Fab")
		)
		(fp_line
			(start 0.120396 0.3048)
			(end 0.120396 0.2794)
			(stroke
				(width 0.1)
				(type default)
			)
			(layer "F.Fab")
		)
		(fp_line
			(start 0.120396 0.2794)
			(end -0.12065 0.2794)
			(stroke
				(width 0.1)
				(type default)
			)
			(layer "F.Fab")
		)
		(fp_line
			(start -0.12065 0.3048)
			(end -0.67945 0.3048)
			(stroke
				(width 0.1)
				(type default)
			)
			(layer "F.Fab")
		)
		(fp_line
			(start -0.12065 0.2794)
			(end -0.12065 0.3048)
			(stroke
				(width 0.1)
				(type default)
			)
			(layer "F.Fab")
		)
		(fp_line
			(start -0.12065 -0.2794)
			(end 0.12065 -0.2794)
			(stroke
				(width 0.1)
				(type default)
			)
			(layer "F.Fab")
		)
		(fp_line
			(start -0.12065 -0.305054)
			(end -0.12065 -0.2794)
			(stroke
				(width 0.1)
				(type default)
			)
			(layer "F.Fab")
		)
		(fp_line
			(start -0.67945 0.3048)
			(end -0.67945 -0.305054)
			(stroke
				(width 0.1)
				(type default)
			)
			(layer "F.Fab")
		)
		(fp_line
			(start -0.67945 -0.305054)
			(end -0.12065 -0.305054)
			(stroke
				(width 0.1)
				(type default)
			)
			(layer "F.Fab")
		)
		(pad "1" smd circle
			(at -0.40005 0 180)
			(size 0 0)
			(layers "F.Cu" "F.Mask" "F.Paste")
			(net "SMB_BIC_I2C6_MUX_SSD_0_7_ADC_R_SDA")
		)
		(pad "2" smd circle
			(at 0.40005 0 180)
			(size 0 0)
			(layers "F.Cu" "F.Mask" "F.Paste")
			(net "SMB_SSD7_ADC_SDA")
		)
	)
	(footprint ""
		(layer "F.Cu")
		(at 3.228086 -43.637708 90)
		(property "Reference" "PC675"
			(at 0 0 90)
			(layer "F.SilkS")
			(hide yes)
			(effects
				(font
					(size 1.27 1.27)
				)
			)
		)
		(property "Value" ""
			(at 0 0 90)
			(layer "F.Fab")
			(effects
				(font
					(size 1.27 1.27)
				)
			)
		)
		(duplicate_pad_numbers_are_jumpers no)
		(fp_line
			(start 0.7874 -0.4064)
			(end 0.7874 0.4064)
			(stroke
				(width 0.1524)
				(type default)
			)
			(layer "F.SilkS")
		)
		(fp_line
			(start -0.7874 -0.4064)
			(end 0.7874 -0.4064)
			(stroke
				(width 0.1524)
				(type default)
			)
			(layer "F.SilkS")
		)
		(fp_line
			(start 0.7874 0.4064)
			(end -0.7874 0.4064)
			(stroke
				(width 0.1524)
				(type default)
			)
			(layer "F.SilkS")
		)
		(fp_line
			(start -0.7874 0.4064)
			(end -0.7874 -0.4064)
			(stroke
				(width 0.1524)
				(type default)
			)
			(layer "F.SilkS")
		)
		(fp_line
			(start -0.12065 -0.305054)
			(end -0.12065 -0.2794)
			(stroke
				(width 0.1)
				(type default)
			)
			(layer "F.Fab")
		)
		(fp_line
			(start -0.67945 -0.305054)
			(end -0.12065 -0.305054)
			(stroke
				(width 0.1)
				(type default)
			)
			(layer "F.Fab")
		)
		(fp_line
			(start 0.67945 -0.3048)
			(end 0.67945 0.3048)
			(stroke
				(width 0.1)
				(type default)
			)
			(layer "F.Fab")
		)
		(fp_line
			(start 0.12065 -0.3048)
			(end 0.67945 -0.3048)
			(stroke
				(width 0.1)
				(type default)
			)
			(layer "F.Fab")
		)
		(fp_line
			(start 0.12065 -0.2794)
			(end 0.12065 -0.3048)
			(stroke
				(width 0.1)
				(type default)
			)
			(layer "F.Fab")
		)
		(fp_line
			(start -0.12065 -0.2794)
			(end 0.12065 -0.2794)
			(stroke
				(width 0.1)
				(type default)
			)
			(layer "F.Fab")
		)
		(fp_line
			(start 0.120396 0.2794)
			(end -0.12065 0.2794)
			(stroke
				(width 0.1)
				(type default)
			)
			(layer "F.Fab")
		)
		(fp_line
			(start -0.12065 0.2794)
			(end -0.12065 0.3048)
			(stroke
				(width 0.1)
				(type default)
			)
			(layer "F.Fab")
		)
		(fp_line
			(start 0.67945 0.3048)
			(end 0.120396 0.3048)
			(stroke
				(width 0.1)
				(type default)
			)
			(layer "F.Fab")
		)
		(fp_line
			(start 0.120396 0.3048)
			(end 0.120396 0.2794)
			(stroke
				(width 0.1)
				(type default)
			)
			(layer "F.Fab")
		)
		(fp_line
			(start -0.12065 0.3048)
			(end -0.67945 0.3048)
			(stroke
				(width 0.1)
				(type default)
			)
			(layer "F.Fab")
		)
		(fp_line
			(start -0.67945 0.3048)
			(end -0.67945 -0.305054)
			(stroke
				(width 0.1)
				(type default)
			)
			(layer "F.Fab")
		)
		(pad "1" smd circle
			(at -0.40005 0 90)
			(size 0 0)
			(layers "F.Cu" "F.Mask" "F.Paste")
			(net "P3V3_SSD0_CO_DV_DT")
		)
		(pad "2" smd circle
			(at 0.40005 0 90)
			(size 0 0)
			(layers "F.Cu" "F.Mask" "F.Paste")
			(net "GND")
		)
	)
)
